FILE_TYPE = CONNECTIVITY;
{Allegro Design Entry HDL 17.4-2019 S026 (4007227) 1/17/2022}
"PAGE_NUMBER" = 83;
0"NC";
1"GND\g";
2"GND\g";
3"GND\g";
4"GND\g";
5"GND\g";
6"GND\g";
7"GND\g";
8"GND\g";
9"GND\g";
10"GND\g";
11"GND\g";
12"GND\g";
13"GND\g";
14"GND\g";
15"GND\g";
16"GND\g";
17"P3V3_AUX\g";
18"GND\g";
19"GND\g";
20"FM_BOARD_SKU_ID0";
21"FM_BOARD_SKU_ID3";
22"FM_BOARD_SKU_ID4";
23"FM_BOARD_SKU_ID1";
24"FAB_BMC_REV_ID0";
25"P1V8_AUX\g";
26"FAB_BMC_REV_ID1";
27"FAB_BMC_REV_ID2";
28"PVDD18_S5_P0\g";
29"PVDD18_S5_P0\g";
30"P3V3_AUX\g";
31"P1V8_AUX\g";
32"FAB_REV_ID2";
33"FAB_REV_ID1";
34"FAB_REV_ID0";
35"FM_BOARD_SKU_ID2";
36"SCM_IRQ_N";
37"SCM_IRQ_R_N";
38"SCM_IRQ_1V8_N";
39"FM_BOARD_BMC_SKU_ID2";
40"FM_BOARD_BMC_SKU_ID1";
41"FM_BOARD_BMC_SKU_ID0";
42"FM_BOARD_BMC_SKU_ID3";
43"FM_BOARD_BMC_SKU_ID4";
%"UNIVERSAL_GND"
"1","(-8375,2925)","0","pure_quanta_power","I100";
;
BOM_COST"OCP3.0 "
CDS_LIB"pure_quanta_power"
HDL_POWER"GND";
"A"1;
%"UNIVERSAL_GND"
"1","(-8050,2925)","0","pure_quanta_power","I101";
;
BOM_COST"OCP3.0 "
CDS_LIB"pure_quanta_power"
HDL_POWER"GND";
"A"2;
%"UNIVERSAL_GND"
"1","(-7700,2925)","0","pure_quanta_power","I102";
;
BOM_COST"OCP3.0 "
CDS_LIB"pure_quanta_power"
HDL_POWER"GND";
"A"3;
%"UNIVERSAL_GND"
"1","(-7350,2925)","0","pure_quanta_power","I103";
;
BOM_COST"OCP3.0 "
CDS_LIB"pure_quanta_power"
HDL_POWER"GND";
"A"4;
%"UNIVERSAL_GND"
"1","(-8700,650)","0","pure_quanta_power","I104";
;
BOM_COST"OCP3.0 "
CDS_LIB"pure_quanta_power"
HDL_POWER"GND";
"A"5;
%"UNIVERSAL_GND"
"1","(-8375,650)","0","pure_quanta_power","I105";
;
BOM_COST"OCP3.0 "
CDS_LIB"pure_quanta_power"
HDL_POWER"GND";
"A"6;
%"UNIVERSAL_GND"
"1","(-8050,650)","0","pure_quanta_power","I106";
;
BOM_COST"OCP3.0 "
CDS_LIB"pure_quanta_power"
HDL_POWER"GND";
"A"7;
%"UNIVERSAL_GND"
"1","(-7700,650)","0","pure_quanta_power","I107";
;
BOM_COST"OCP3.0 "
CDS_LIB"pure_quanta_power"
HDL_POWER"GND";
"A"8;
%"UNIVERSAL_GND"
"1","(-7350,650)","0","pure_quanta_power","I108";
;
BOM_COST"OCP3.0 "
CDS_LIB"pure_quanta_power"
HDL_POWER"GND";
"A"9;
%"UNIVERSAL_GND"
"1","(-3650,3225)","0","pure_quanta_power","I109";
;
CDS_LIB"pure_quanta_power"
BOM_COST"OCP3.0 "
HDL_POWER"GND";
"A"10;
%"UNIVERSAL_GND"
"1","(-3300,3225)","0","pure_quanta_power","I110";
;
CDS_LIB"pure_quanta_power"
BOM_COST"OCP3.0 "
HDL_POWER"GND";
"A"11;
%"UNIVERSAL_GND"
"1","(-2950,3225)","0","pure_quanta_power","I111";
;
CDS_LIB"pure_quanta_power"
BOM_COST"OCP3.0 "
HDL_POWER"GND";
"A"12;
%"UNIVERSAL_GND"
"1","(-3650,575)","0","pure_quanta_power","I112";
;
BOM_COST"OCP3.0 "
CDS_LIB"pure_quanta_power"
HDL_POWER"GND";
"A"13;
%"UNIVERSAL_GND"
"1","(-3300,575)","0","pure_quanta_power","I113";
;
BOM_COST"OCP3.0 "
CDS_LIB"pure_quanta_power"
HDL_POWER"GND";
"A"14;
%"UNIVERSAL_GND"
"1","(-2950,575)","0","pure_quanta_power","I114";
;
BOM_COST"OCP3.0 "
CDS_LIB"pure_quanta_power"
HDL_POWER"GND";
"A"15;
%"Q_RES"
"2","(-8700,4350)","0","pure_quanta","I115";
;
LOCATION"R6120"
$SEC"1"
CDS_SEC"1"
TOLERANCE"1%"
VALUE"1K"
WATTAGE"1/16W"
MATERIAL"CHIP"
PACK_TYPE"0402LF"
CDS_LIB"pure_quanta"
PART_NUMBER"CS21002FB06";
"A"
$PN"1"29;
"B"
$PN"2"22;
%"Q_RES"
"2","(-8700,3400)","0","pure_quanta","I116";
;
LOCATION"R6125"
$SEC"1"
CDS_SEC"1"
MATERIAL"EMPTY"
PACK_TYPE"0402LF"
WATTAGE"1/16W"
TOLERANCE"1%"
VALUE"1K"
CDS_LIB"pure_quanta"
PART_NUMBER"CS21002FB06";
"A"
$PN"1"22;
"B"
$PN"2"19;
%"Q_RES"
"2","(-8700,2075)","0","pure_quanta","I117";
;
LOCATION"R6136"
$SEC"1"
CDS_SEC"1"
TOLERANCE"1%"
MATERIAL"CHIP"
PACK_TYPE"0402LF"
VALUE"1K"
WATTAGE"1/16W"
CDS_LIB"pure_quanta"
PART_NUMBER"CS21002FB06";
"A"
$PN"1"30;
"B"
$PN"2"43;
%"Q_RES"
"2","(-8700,1125)","0","pure_quanta","I118";
;
LOCATION"R6141"
$SEC"1"
CDS_SEC"1"
PACK_TYPE"0402LF"
MATERIAL"EMPTY"
WATTAGE"1/16W"
TOLERANCE"1%"
VALUE"1K"
CDS_LIB"pure_quanta"
PART_NUMBER"CS21002FB06";
"A"
$PN"1"43;
"B"
$PN"2"5;
%"Q_RES"
"2","(-8375,3400)","0","pure_quanta","I119";
;
LOCATION"R6126"
$SEC"1"
CDS_SEC"1"
VALUE"1K"
TOLERANCE"1%"
MATERIAL"CHIP"
PACK_TYPE"0402LF"
WATTAGE"1/16W"
CDS_LIB"pure_quanta"
PART_NUMBER"CS21002FB06";
"A"
$PN"1"21;
"B"
$PN"2"1;
%"Q_RES"
"2","(-8375,4350)","0","pure_quanta","I120";
;
LOCATION"R6121"
$SEC"1"
CDS_SEC"1"
WATTAGE"1/16W"
PACK_TYPE"0402LF"
VALUE"1K"
TOLERANCE"1%"
MATERIAL"EMPTY"
CDS_LIB"pure_quanta"
PART_NUMBER"CS21002FB06";
"A"
$PN"1"29;
"B"
$PN"2"21;
%"Q_RES"
"2","(-8375,2075)","0","pure_quanta","I121";
;
LOCATION"R6137"
$SEC"1"
CDS_SEC"1"
PACK_TYPE"0402LF"
MATERIAL"EMPTY"
TOLERANCE"1%"
VALUE"1K"
WATTAGE"1/16W"
CDS_LIB"pure_quanta"
PART_NUMBER"CS21002FB06";
"A"
$PN"1"30;
"B"
$PN"2"42;
%"Q_RES"
"2","(-8375,1125)","0","pure_quanta","I122";
;
LOCATION"R6142"
$SEC"1"
CDS_SEC"1"
PACK_TYPE"0402LF"
MATERIAL"CHIP"
WATTAGE"1/16W"
TOLERANCE"1%"
VALUE"1K"
CDS_LIB"pure_quanta"
PART_NUMBER"CS21002FB06";
"A"
$PN"1"42;
"B"
$PN"2"6;
%"Q_RES"
"2","(-3650,4650)","0","pure_quanta","I131";
;
LOCATION"R6130"
$SEC"1"
CDS_SEC"1"
PACK_TYPE"0402LF"
MATERIAL"CHIP"
VALUE"1K"
WATTAGE"1/16W"
TOLERANCE"1%"
CDS_LIB"pure_quanta"
PART_NUMBER"CS21002FB06";
"A"
$PN"1"28;
"B"
$PN"2"32;
%"Q_RES"
"2","(-3650,3700)","0","pure_quanta","I132";
;
LOCATION"R6133"
$SEC"1"
CDS_SEC"1"
PACK_TYPE"0402LF"
MATERIAL"EMPTY"
WATTAGE"1/16W"
VALUE"1K"
TOLERANCE"1%"
CDS_LIB"pure_quanta"
PART_NUMBER"CS21002FB06";
"A"
$PN"1"32;
"B"
$PN"2"10;
%"Q_RES"
"2","(-3300,3700)","0","pure_quanta","I133";
;
LOCATION"R6134"
$SEC"1"
CDS_SEC"1"
PACK_TYPE"0402LF"
MATERIAL"CHIP"
WATTAGE"1/16W"
TOLERANCE"1%"
VALUE"1K"
CDS_LIB"pure_quanta"
PART_NUMBER"CS21002FB06";
"A"
$PN"1"33;
"B"
$PN"2"11;
%"Q_RES"
"2","(-3300,4650)","0","pure_quanta","I134";
;
LOCATION"R6131"
$SEC"1"
CDS_SEC"1"
VALUE"1K"
TOLERANCE"1%"
MATERIAL"EMPTY"
WATTAGE"1/16W"
PACK_TYPE"0402LF"
CDS_LIB"pure_quanta"
PART_NUMBER"CS21002FB06";
"A"
$PN"1"28;
"B"
$PN"2"33;
%"Q_RES"
"2","(-2950,4650)","0","pure_quanta","I135";
;
LOCATION"R6132"
$SEC"1"
CDS_SEC"1"
PACK_TYPE"0402LF"
TOLERANCE"1%"
VALUE"1K"
MATERIAL"EMPTY"
WATTAGE"1/16W"
CDS_LIB"pure_quanta"
PART_NUMBER"CS21002FB06";
"A"
$PN"1"28;
"B"
$PN"2"34;
%"Q_RES"
"2","(-2950,3700)","0","pure_quanta","I136";
;
LOCATION"R6135"
$SEC"1"
CDS_SEC"1"
VALUE"1K"
TOLERANCE"1%"
WATTAGE"1/16W"
MATERIAL"CHIP"
PACK_TYPE"0402LF"
CDS_LIB"pure_quanta"
PART_NUMBER"CS21002FB06";
"A"
$PN"1"34;
"B"
$PN"2"12;
%"Q_RES"
"2","(-3650,1050)","0","pure_quanta","I137";
;
LOCATION"R6149"
$SEC"1"
CDS_SEC"1"
WATTAGE"1/16W"
MATERIAL"EMPTY"
PACK_TYPE"0402LF"
TOLERANCE"1%"
VALUE"1K"
CDS_LIB"pure_quanta"
PART_NUMBER"CS21002FB06";
"A"
$PN"1"27;
"B"
$PN"2"13;
%"Q_RES"
"2","(-3650,2000)","0","pure_quanta","I138";
;
LOCATION"R6146"
$SEC"1"
CDS_SEC"1"
TOLERANCE"1%"
VALUE"1K"
WATTAGE"1/16W"
MATERIAL"CHIP"
PACK_TYPE"0402LF"
CDS_LIB"pure_quanta"
PART_NUMBER"CS21002FB06";
"A"
$PN"1"25;
"B"
$PN"2"27;
%"Q_RES"
"2","(-3300,1050)","0","pure_quanta","I139";
;
LOCATION"R6150"
$SEC"1"
CDS_SEC"1"
WATTAGE"1/16W"
PACK_TYPE"0402LF"
TOLERANCE"1%"
MATERIAL"CHIP"
VALUE"1K"
CDS_LIB"pure_quanta"
PART_NUMBER"CS21002FB06";
"A"
$PN"1"26;
"B"
$PN"2"14;
%"Q_RES"
"2","(-3300,2000)","0","pure_quanta","I140";
;
LOCATION"R6147"
$SEC"1"
CDS_SEC"1"
TOLERANCE"1%"
VALUE"1K"
MATERIAL"EMPTY"
WATTAGE"1/16W"
PACK_TYPE"0402LF"
CDS_LIB"pure_quanta"
PART_NUMBER"CS21002FB06";
"A"
$PN"1"25;
"B"
$PN"2"26;
%"Q_RES"
"2","(-2950,1050)","0","pure_quanta","I141";
;
LOCATION"R6151"
$SEC"1"
CDS_SEC"1"
WATTAGE"1/16W"
MATERIAL"CHIP"
TOLERANCE"1%"
PACK_TYPE"0402LF"
VALUE"1K"
CDS_LIB"pure_quanta"
PART_NUMBER"CS21002FB06";
"A"
$PN"1"24;
"B"
$PN"2"15;
%"Q_RES"
"2","(-2950,2000)","0","pure_quanta","I142";
;
LOCATION"R6148"
$SEC"1"
CDS_SEC"1"
TOLERANCE"1%"
MATERIAL"EMPTY"
PACK_TYPE"0402LF"
WATTAGE"1/16W"
VALUE"1K"
CDS_LIB"pure_quanta"
PART_NUMBER"CS21002FB06";
"A"
$PN"1"25;
"B"
$PN"2"24;
%"Q_RES"
"2","(-2975,5850)","2","pure_quanta","I22";
;
LOCATION"R996"
$SEC"1"
CDS_SEC"1"
PACK_TYPE"0402LF"
TOLERANCE"5%"
MATERIAL"CHIP"
WATTAGE"1/16W"
VALUE"4.7K"
BOM_COST"OCP3.0 "
CDS_LIB"pure_quanta"
PART_NUMBER"CS24702JB10";
"A"
$PN"1"31;
"B"
$PN"2"38;
%"UNIVERSAL_GND"
"1","(-2850,5650)","0","pure_quanta_power","I23";
;
CDS_LIB"pure_quanta_power"
BOM_COST"OCP3.0 "
HDL_POWER"GND";
"A"16;
%"Q_CAP"
"1","(-2850,5850)","0","pure_quanta","I24";
;
LOCATION"C552"
$SEC"1"
CDS_SEC"1"
PACK_TYPE"0402"
VALUE"0.1UF"
MATERIAL"X7R"
TOLERANCE"10%"
VOLTAGE"25V"
CDS_LIB"pure_quanta"
BOM_COST"OCP3.0 "
PART_NUMBER"CH4104K1B00";
"B"
$PN"2"16;
"A"
$PN"1"31;
%"UNIVERSAL_POWER"
"1","(-2850,6150)","0","pure_quanta_power","I25";
;
HDL_POWER"P1V8_AUX"
CDS_LIB"pure_quanta_power"
BOM_COST"OCP3.0 ";
"A"31;
%"SN74LVC1G07DBVR"
"1","(-2250,5525)","0","pure_quanta","I26";
;
LOCATION"U92"
$SEC"1"
CDS_SEC"1"
PACK_TYPE"SMLF"
VALUE"SN74LVC1G07DBVR"
MATERIAL"IC"
CDS_LIB"pure_quanta"
NEEDS_NO_SIZE"TRUE"
PART_NUMBER"AL1G0007024";
"NC"
$PN"1"0;
"Y"
$PN"4"37;
"GND"
$PN"3"18;
"A"
$PN"2"38;
"VCC"
$PN"5"31;
%"Q_RES"
"1","(-1500,5525)","0","pure_quanta","I27";
;
LOCATION"R71"
$SEC"1"
CDS_SEC"1"
VALUE"33"
PACK_TYPE"0402LF"
TOLERANCE"5%"
MATERIAL"CHIP"
WATTAGE"1/16W"
BOM_COST"MEM"
CDS_LIB"pure_quanta"
PART_NUMBER"CS03302JB10";
"B"
$PN"2"36;
"A"
$PN"1"37;
%"Q_RES"
"2","(-925,5775)","0","pure_quanta","I29";
;
LOCATION"R1338"
$SEC"1"
CDS_SEC"1"
PACK_TYPE"0402LF"
VALUE"4.7K"
TOLERANCE"5%"
WATTAGE"1/16W"
MATERIAL"CHIP"
CDS_LIB"pure_quanta"
BOM_COST"OCP3.0 "
PART_NUMBER"CS24702JB10";
"A"
$PN"1"17;
"B"
$PN"2"36;
%"UNIVERSAL_POWER"
"1","(-925,6050)","0","pure_quanta_power","I30";
;
HDL_POWER"P3V3_AUX"
BOM_COST"OCP3.0 "
CDS_LIB"pure_quanta_power";
"A"17;
%"Q_RES"
"2","(-8050,1125)","0","pure_quanta","I36";
;
LOCATION"R6143"
$SEC"1"
CDS_SEC"1"
WATTAGE"1/16W"
TOLERANCE"1%"
MATERIAL"CHIP"
VALUE"1K"
PACK_TYPE"0402LF"
CDS_LIB"pure_quanta"
PART_NUMBER"CS21002FB06";
"A"
$PN"1"39;
"B"
$PN"2"7;
%"Q_RES"
"2","(-8050,2075)","0","pure_quanta","I39";
;
LOCATION"R6138"
$SEC"1"
CDS_SEC"1"
TOLERANCE"1%"
VALUE"1K"
MATERIAL"EMPTY"
WATTAGE"1/16W"
PACK_TYPE"0402LF"
CDS_LIB"pure_quanta"
PART_NUMBER"CS21002FB06";
"A"
$PN"1"30;
"B"
$PN"2"39;
%"UNIVERSAL_POWER"
"1","(-8700,2600)","0","pure_quanta_power","I40";
;
HDL_POWER"P3V3_AUX"
CDS_LIB"pure_quanta_power";
"A"30;
%"Q_RES"
"2","(-8050,3400)","0","pure_quanta","I46";
;
LOCATION"R6127"
$SEC"1"
CDS_SEC"1"
VALUE"1K"
TOLERANCE"1%"
MATERIAL"CHIP"
PACK_TYPE"0402LF"
WATTAGE"1/16W"
CDS_LIB"pure_quanta"
PART_NUMBER"CS21002FB06";
"A"
$PN"1"35;
"B"
$PN"2"2;
%"UNIVERSAL_POWER"
"1","(-8700,4875)","0","pure_quanta_power","I48";
;
HDL_POWER"PVDD18_S5_P0"
CDS_LIB"pure_quanta_power";
"A"29;
%"Q_RES"
"2","(-8050,4350)","0","pure_quanta","I50";
;
LOCATION"R6122"
$SEC"1"
CDS_SEC"1"
MATERIAL"EMPTY"
PACK_TYPE"0402LF"
WATTAGE"1/16W"
TOLERANCE"1%"
VALUE"1K"
CDS_LIB"pure_quanta"
PART_NUMBER"CS21002FB06";
"A"
$PN"1"29;
"B"
$PN"2"35;
%"Q_RES"
"2","(-7700,1125)","0","pure_quanta","I52";
;
LOCATION"R6144"
$SEC"1"
CDS_SEC"1"
MATERIAL"CHIP"
WATTAGE"1/16W"
TOLERANCE"1%"
VALUE"1K"
PACK_TYPE"0402LF"
CDS_LIB"pure_quanta"
PART_NUMBER"CS21002FB06";
"A"
$PN"1"40;
"B"
$PN"2"8;
%"Q_RES"
"2","(-7350,1125)","0","pure_quanta","I54";
;
LOCATION"R6145"
$SEC"1"
CDS_SEC"1"
TOLERANCE"1%"
WATTAGE"1/16W"
MATERIAL"CHIP"
VALUE"1K"
PACK_TYPE"0402LF"
CDS_LIB"pure_quanta"
PART_NUMBER"CS21002FB06";
"A"
$PN"1"41;
"B"
$PN"2"9;
%"Q_RES"
"2","(-7700,2075)","0","pure_quanta","I55";
;
LOCATION"R6139"
$SEC"1"
CDS_SEC"1"
PACK_TYPE"0402LF"
TOLERANCE"1%"
VALUE"1K"
WATTAGE"1/16W"
MATERIAL"EMPTY"
CDS_LIB"pure_quanta"
PART_NUMBER"CS21002FB06";
"A"
$PN"1"30;
"B"
$PN"2"40;
%"Q_RES"
"2","(-7350,2075)","0","pure_quanta","I56";
;
LOCATION"R6140"
$SEC"1"
CDS_SEC"1"
MATERIAL"EMPTY"
PACK_TYPE"0402LF"
VALUE"1K"
TOLERANCE"1%"
WATTAGE"1/16W"
CDS_LIB"pure_quanta"
PART_NUMBER"CS21002FB06";
"A"
$PN"1"30;
"B"
$PN"2"41;
%"Q_RES"
"2","(-7700,3400)","0","pure_quanta","I64";
;
LOCATION"R6128"
$SEC"1"
CDS_SEC"1"
TOLERANCE"1%"
WATTAGE"1/16W"
VALUE"1K"
MATERIAL"CHIP"
PACK_TYPE"0402LF"
CDS_LIB"pure_quanta"
PART_NUMBER"CS21002FB06";
"A"
$PN"1"23;
"B"
$PN"2"3;
%"Q_RES"
"2","(-7350,3400)","0","pure_quanta","I65";
;
LOCATION"R6129"
$SEC"1"
CDS_SEC"1"
PACK_TYPE"0402LF"
WATTAGE"1/16W"
VALUE"1K"
TOLERANCE"1%"
MATERIAL"CHIP"
CDS_LIB"pure_quanta"
PART_NUMBER"CS21002FB06";
"A"
$PN"1"20;
"B"
$PN"2"4;
%"Q_RES"
"2","(-7700,4350)","0","pure_quanta","I71";
;
LOCATION"R6123"
$SEC"1"
CDS_SEC"1"
VALUE"1K"
MATERIAL"EMPTY"
WATTAGE"1/16W"
TOLERANCE"1%"
PACK_TYPE"0402LF"
CDS_LIB"pure_quanta"
PART_NUMBER"CS21002FB06";
"A"
$PN"1"29;
"B"
$PN"2"23;
%"Q_RES"
"2","(-7350,4350)","0","pure_quanta","I72";
;
LOCATION"R6124"
$SEC"1"
CDS_SEC"1"
TOLERANCE"1%"
VALUE"1K"
MATERIAL"EMPTY"
WATTAGE"1/16W"
PACK_TYPE"0402LF"
CDS_LIB"pure_quanta"
PART_NUMBER"CS21002FB06";
"A"
$PN"1"29;
"B"
$PN"2"20;
%"UNIVERSAL_POWER"
"1","(-3650,2525)","0","pure_quanta_power","I82";
;
HDL_POWER"P1V8_AUX"
CDS_LIB"pure_quanta_power";
"A"25;
%"UNIVERSAL_GND"
"1","(-2500,5250)","0","pure_quanta_power","I9";
;
CDS_LIB"pure_quanta_power"
BOM_COST"OCP3.0 "
HDL_POWER"GND";
"A"18;
%"UNIVERSAL_POWER"
"1","(-3650,5175)","0","pure_quanta_power","I97";
;
HDL_POWER"PVDD18_S5_P0"
CDS_LIB"pure_quanta_power";
"A"28;
%"UNIVERSAL_GND"
"1","(-8700,2925)","0","pure_quanta_power","I99";
;
BOM_COST"OCP3.0 "
CDS_LIB"pure_quanta_power"
HDL_POWER"GND";
"A"19;
END.
